# S9S_MB_2U (Grand Teton) — schematic netlist excerpt (pin names and nets, part order shuffled) for the footprints in the layout excerpt that follows; sources: Cadence DE-HDL packaged netlist, KiCad conversion of 03242023_DA0F0TMBIJ0_F0T_Motherboard_J_brd_V01_OCP.brd

R3770  Q_RES  0 5% CHIP  pkg 0402LF  page 246 : A = GPU_PRSNT ; B = GPU_PRSNT_R
R4474  Q_RES  0 5% CHIP  pkg 0402LF  page 196 : A = USB2_0_DN ; B = USB2_HOST_PCH_0_DN

(kicad_pcb
	(version 20260206)
	(generator "pcbnew")
	(generator_version "10.0")
	(general
		(thickness 1.6)
		(legacy_teardrops no)
	)
	(paper "A4")
	(title_block
		(title "03242023_DA0F0TMBIJ0_F0T_Motherboard_J_brd_V01_OCP.brd")
		(comment 1 "Grand Teton / footprints 2607-2608 of 6105")
	)
	(layers
		(0 "F.Cu" signal "TOP")
		(4 "In1.Cu" signal "GND")
		(6 "In2.Cu" signal "IN1")
		(8 "In3.Cu" signal "GND1")
		(10 "In4.Cu" signal "IN2")
		(12 "In5.Cu" signal "GND2")
		(14 "In6.Cu" signal "IN3")
		(16 "In7.Cu" signal "GND3")
		(18 "In8.Cu" signal "VCC")
		(20 "In9.Cu" signal "VCC1")
		(22 "In10.Cu" signal "GND4")
		(24 "In11.Cu" signal "IN4")
		(26 "In12.Cu" signal "GND5")
		(28 "In13.Cu" signal "IN5")
		(30 "In14.Cu" signal "GND6")
		(32 "In15.Cu" signal "IN6")
		(34 "In16.Cu" signal "GND7")
		(2 "B.Cu" signal "BOTTOM")
		(9 "F.Adhes" user "F.Adhesive")
		(11 "B.Adhes" user "B.Adhesive")
		(13 "F.Paste" user "Package Geometry/Pastemask Top")
		(15 "B.Paste" user "Package Geometry/Pastemask Bottom")
		(5 "F.SilkS" user "Ref Des/Silkscreen Top")
		(7 "B.SilkS" user "Ref Des/Silkscreen Bottom")
		(1 "F.Mask" user "Board Geometry/Soldermask Top")
		(3 "B.Mask" user "Board Geometry/Soldermask Bottom")
		(17 "Dwgs.User" user "User.Drawings")
		(19 "Cmts.User" user "User.Comments")
		(21 "Eco1.User" user "User.Eco1")
		(23 "Eco2.User" user "User.Eco2")
		(25 "Edge.Cuts" user "Board Geometry/Outline")
		(27 "Margin" user)
		(31 "F.CrtYd" user "Package Geometry/Place Bound Top")
		(29 "B.CrtYd" user "Package Geometry/Place Bound Bottom")
		(35 "F.Fab" user "Ref Des/Assembly Top")
		(33 "B.Fab" user "Ref Des/Assembly Bottom")
	)
	(footprint ""
		(layer "F.Cu")
		(at 191.861186 -438.17413 -90)
		(property "Reference" "R3770"
			(at 0 0 270)
			(layer "F.SilkS")
			(hide yes)
			(effects
				(font
					(size 1.27 1.27)
				)
			)
		)
		(property "Value" ""
			(at 0 0 270)
			(layer "F.Fab")
			(effects
				(font
					(size 1.27 1.27)
				)
			)
		)
		(duplicate_pad_numbers_are_jumpers no)
		(fp_line
			(start -0.7874 0.4064)
			(end -0.7874 -0.4064)
			(stroke
				(width 0.1524)
				(type default)
			)
			(layer "F.SilkS")
		)
		(fp_line
			(start 0.7874 0.4064)
			(end -0.7874 0.4064)
			(stroke
				(width 0.1524)
				(type default)
			)
			(layer "F.SilkS")
		)
		(fp_line
			(start -0.7874 -0.4064)
			(end 0.7874 -0.4064)
			(stroke
				(width 0.1524)
				(type default)
			)
			(layer "F.SilkS")
		)
		(fp_line
			(start 0.7874 -0.4064)
			(end 0.7874 0.4064)
			(stroke
				(width 0.1524)
				(type default)
			)
			(layer "F.SilkS")
		)
		(fp_line
			(start -0.67945 0.3048)
			(end -0.67945 -0.305054)
			(stroke
				(width 0.1)
				(type default)
			)
			(layer "F.Fab")
		)
		(fp_line
			(start -0.12065 0.3048)
			(end -0.67945 0.3048)
			(stroke
				(width 0.1)
				(type default)
			)
			(layer "F.Fab")
		)
		(fp_line
			(start 0.120396 0.3048)
			(end 0.120396 0.2794)
			(stroke
				(width 0.1)
				(type default)
			)
			(layer "F.Fab")
		)
		(fp_line
			(start 0.67945 0.3048)
			(end 0.120396 0.3048)
			(stroke
				(width 0.1)
				(type default)
			)
			(layer "F.Fab")
		)
		(fp_line
			(start -0.12065 0.2794)
			(end -0.12065 0.3048)
			(stroke
				(width 0.1)
				(type default)
			)
			(layer "F.Fab")
		)
		(fp_line
			(start 0.120396 0.2794)
			(end -0.12065 0.2794)
			(stroke
				(width 0.1)
				(type default)
			)
			(layer "F.Fab")
		)
		(fp_line
			(start -0.12065 -0.2794)
			(end 0.12065 -0.2794)
			(stroke
				(width 0.1)
				(type default)
			)
			(layer "F.Fab")
		)
		(fp_line
			(start 0.12065 -0.2794)
			(end 0.12065 -0.3048)
			(stroke
				(width 0.1)
				(type default)
			)
			(layer "F.Fab")
		)
		(fp_line
			(start 0.12065 -0.3048)
			(end 0.67945 -0.3048)
			(stroke
				(width 0.1)
				(type default)
			)
			(layer "F.Fab")
		)
		(fp_line
			(start 0.67945 -0.3048)
			(end 0.67945 0.3048)
			(stroke
				(width 0.1)
				(type default)
			)
			(layer "F.Fab")
		)
		(fp_line
			(start -0.67945 -0.305054)
			(end -0.12065 -0.305054)
			(stroke
				(width 0.1)
				(type default)
			)
			(layer "F.Fab")
		)
		(fp_line
			(start -0.12065 -0.305054)
			(end -0.12065 -0.2794)
			(stroke
				(width 0.1)
				(type default)
			)
			(layer "F.Fab")
		)
		(pad "1" smd circle
			(at -0.40005 0 270)
			(size 0 0)
			(layers "F.Cu" "F.Mask" "F.Paste")
			(net "GPU_PRSNT")
		)
		(pad "2" smd circle
			(at 0.40005 0 270)
			(size 0 0)
			(layers "F.Cu" "F.Mask" "F.Paste")
			(net "GPU_PRSNT_R")
		)
	)
	(footprint ""
		(layer "F.Cu")
		(at 160.28035 -44.632626 90)
		(property "Reference" "R4474"
			(at 0 0 90)
			(layer "F.SilkS")
			(hide yes)
			(effects
				(font
					(size 1.27 1.27)
				)
			)
		)
		(property "Value" ""
			(at 0 0 90)
			(layer "F.Fab")
			(effects
				(font
					(size 1.27 1.27)
				)
			)
		)
		(duplicate_pad_numbers_are_jumpers no)
		(fp_line
			(start 0.7874 0.4064)
			(end -0.7874 0.4064)
			(stroke
				(width 0.1524)
				(type default)
			)
			(layer "F.SilkS")
		)
		(fp_line
			(start -0.7874 0.4064)
			(end -0.7874 -0.4064)
			(stroke
				(width 0.1524)
				(type default)
			)
			(layer "F.SilkS")
		)
		(fp_line
			(start -0.12065 -0.305054)
			(end -0.12065 -0.2794)
			(stroke
				(width 0.1)
				(type default)
			)
			(layer "F.Fab")
		)
		(fp_line
			(start -0.67945 -0.305054)
			(end -0.12065 -0.305054)
			(stroke
				(width 0.1)
				(type default)
			)
			(layer "F.Fab")
		)
		(fp_line
			(start 0.67945 -0.3048)
			(end 0.67945 0.3048)
			(stroke
				(width 0.1)
				(type default)
			)
			(layer "F.Fab")
		)
		(fp_line
			(start 0.12065 -0.3048)
			(end 0.67945 -0.3048)
			(stroke
				(width 0.1)
				(type default)
			)
			(layer "F.Fab")
		)
		(fp_line
			(start 0.12065 -0.2794)
			(end 0.12065 -0.3048)
			(stroke
				(width 0.1)
				(type default)
			)
			(layer "F.Fab")
		)
		(fp_line
			(start -0.12065 -0.2794)
			(end 0.12065 -0.2794)
			(stroke
				(width 0.1)
				(type default)
			)
			(layer "F.Fab")
		)
		(fp_line
			(start 0.120396 0.2794)
			(end -0.12065 0.2794)
			(stroke
				(width 0.1)
				(type default)
			)
			(layer "F.Fab")
		)
		(fp_line
			(start -0.12065 0.2794)
			(end -0.12065 0.3048)
			(stroke
				(width 0.1)
				(type default)
			)
			(layer "F.Fab")
		)
		(fp_line
			(start 0.67945 0.3048)
			(end 0.120396 0.3048)
			(stroke
				(width 0.1)
				(type default)
			)
			(layer "F.Fab")
		)
		(fp_line
			(start 0.120396 0.3048)
			(end 0.120396 0.2794)
			(stroke
				(width 0.1)
				(type default)
			)
			(layer "F.Fab")
		)
		(fp_line
			(start -0.12065 0.3048)
			(end -0.67945 0.3048)
			(stroke
				(width 0.1)
				(type default)
			)
			(layer "F.Fab")
		)
		(fp_line
			(start -0.67945 0.3048)
			(end -0.67945 -0.305054)
			(stroke
				(width 0.1)
				(type default)
			)
			(layer "F.Fab")
		)
		(pad "1" smd rect
			(at -0.40005 0 270)
			(size 0.4572 0.508)
			(layers "F.Cu" "F.Mask" "F.Paste")
			(net "USB2_0_DN")
		)
		(pad "2" smd rect
			(at 0.40005 0 270)
			(size 0.4572 0.508)
			(layers "F.Cu" "F.Mask" "F.Paste")
			(net "USB2_HOST_PCH_0_DN")
		)
	)
)
